(kicad_pcb
	(version 20221018)
	(generator pcbnew)
	(general
    (thickness 1.7403)
  )
	(paper "A4")
	(title_block
    (title "Data Center RDIMM DDR4 Tester")
    (date "2024-09-30")
    (rev "1.2.4")
		(comment 9 "footprints 393-402 of 690")
	)
	(layers
    (0 "F.Cu" signal)
    (1 "In1.Cu" power)
    (2 "In2.Cu" signal)
    (3 "In3.Cu" power)
    (4 "In4.Cu" power)
    (5 "In5.Cu" signal)
    (6 "In6.Cu" power)
    (7 "In7.Cu" signal)
    (8 "In8.Cu" power)
    (9 "In9.Cu" signal)
    (10 "In10.Cu" power)
    (31 "B.Cu" signal)
    (32 "B.Adhes" user "B.Adhesive")
    (33 "F.Adhes" user "F.Adhesive")
    (34 "B.Paste" user)
    (35 "F.Paste" user)
    (36 "B.SilkS" user "B.Silkscreen")
    (37 "F.SilkS" user "F.Silkscreen")
    (38 "B.Mask" user)
    (39 "F.Mask" user)
    (40 "Dwgs.User" user "User.Drawings")
    (41 "Cmts.User" user "User.Comments")
    (42 "Eco1.User" user "User.Eco1")
    (43 "Eco2.User" user "User.Eco2")
    (44 "Edge.Cuts" user)
    (45 "Margin" user)
    (46 "B.CrtYd" user "B.Courtyard")
    (47 "F.CrtYd" user "F.Courtyard")
    (48 "B.Fab" user)
    (49 "F.Fab" user)
  )
	(footprint "data-center-rdimm-ddr4-tester-footprints:C_0402_1005Metric" (layer "B.Cu")
    (at 158.95 100.55 -90)
    (descr "Capacitor SMD 0402")
    (tags "capacitor SMD 0402")
    (property "Author" "Antmicro")
    (property "Dielectric" "")
    (property "License" "Apache-2.0")
    (property "MPN" "C1005X5R1E474M050BB")
    (property "Manufacturer" "TDK")
    (property "Sheetfile" "ethernet.kicad_sch")
    (property "Sheetname" "Ethernet")
    (property "Val" "470n")
    (property "Voltage" "")
    (property "ki_description" " ")
    (attr smd)
    (fp_text reference "C125" (at -0.04 1.52 90) (layer "B.SilkS")
        (effects (font (size 0.7 0.7) (thickness 0.15)) (justify left bottom mirror))
    )
    (fp_text value "C_470n_0402" (at 0 -1.4 90) (layer "B.Fab") hide
        (effects (font (size 0.7 0.7) (thickness 0.15)) (justify left bottom mirror))
    )
    (fp_text user "${REFERENCE}" (at -0.932 -3.168 90) (layer "B.Fab") hide
        (effects (font (size 0.7 0.7) (thickness 0.15)) (justify left bottom mirror))
    )
    (fp_text user "License: Apache-2.0" (at -0.932 -5.17 90) (layer "B.Fab") hide
        (effects (font (size 0.7 0.7) (thickness 0.15)) (justify left bottom mirror))
    )
    (fp_text user "Author: Antmicro" (at -0.932 -4.17 90) (layer "B.Fab") hide
        (effects (font (size 0.7 0.7) (thickness 0.15)) (justify left bottom mirror))
    )
    (fp_rect (start -0.94 0.47) (end 0.94 -0.47)
      (stroke (width 0.05) (type solid)) (fill none) (layer "B.CrtYd"))
    (fp_rect (start -0.499 0.249) (end 0.499 -0.249)
      (stroke (width 0.15) (type solid)) (fill none) (layer "B.Fab"))
    (pad "1" smd roundrect (at -0.484 0 270) (size 0.59 0.64) (layers "B.Cu" "B.Paste" "B.Mask") (roundrect_rratio 0.25)
      (net 177 "/Ethernet/AVDDL") (pintype "passive"))
    (pad "2" smd roundrect (at 0.484 0 270) (size 0.59 0.64) (layers "B.Cu" "B.Paste" "B.Mask") (roundrect_rratio 0.25)
      (net 9 "GND") (pintype "passive"))
  )
	(footprint "data-center-rdimm-ddr4-tester-footprints:C_0402_1005Metric" (layer "B.Cu")
    (at 159.586328 93.020008 -90)
    (descr "Capacitor SMD 0402")
    (tags "capacitor SMD 0402")
    (property "Author" "Antmicro")
    (property "Dielectric" "")
    (property "License" "Apache-2.0")
    (property "MPN" "C1005X5R1E474M050BB")
    (property "Manufacturer" "TDK")
    (property "Sheetfile" "ethernet.kicad_sch")
    (property "Sheetname" "Ethernet")
    (property "Val" "470n")
    (property "Voltage" "")
    (property "ki_description" " ")
    (attr smd)
    (fp_text reference "C126" (at -1.449008 -6.503672 90) (layer "B.SilkS")
        (effects (font (size 0.7 0.7) (thickness 0.15)) (justify left bottom mirror))
    )
    (fp_text value "C_470n_0402" (at 0 -1.4 90) (layer "B.Fab") hide
        (effects (font (size 0.7 0.7) (thickness 0.15)) (justify left bottom mirror))
    )
    (fp_text user "License: Apache-2.0" (at -0.932 -5.17 90) (layer "B.Fab") hide
        (effects (font (size 0.7 0.7) (thickness 0.15)) (justify left bottom mirror))
    )
    (fp_text user "Author: Antmicro" (at -0.932 -4.17 90) (layer "B.Fab") hide
        (effects (font (size 0.7 0.7) (thickness 0.15)) (justify left bottom mirror))
    )
    (fp_text user "${REFERENCE}" (at -0.932 -3.168 90) (layer "B.Fab") hide
        (effects (font (size 0.7 0.7) (thickness 0.15)) (justify left bottom mirror))
    )
    (fp_rect (start -0.94 0.47) (end 0.94 -0.47)
      (stroke (width 0.05) (type solid)) (fill none) (layer "B.CrtYd"))
    (fp_rect (start -0.499 0.249) (end 0.499 -0.249)
      (stroke (width 0.15) (type solid)) (fill none) (layer "B.Fab"))
    (pad "1" smd roundrect (at -0.484 0 270) (size 0.59 0.64) (layers "B.Cu" "B.Paste" "B.Mask") (roundrect_rratio 0.25)
      (net 306 "1V2_SYS") (pintype "passive"))
    (pad "2" smd roundrect (at 0.484 0 270) (size 0.59 0.64) (layers "B.Cu" "B.Paste" "B.Mask") (roundrect_rratio 0.25)
      (net 9 "GND") (pintype "passive"))
  )
	(footprint "data-center-rdimm-ddr4-tester-footprints:C_0402_1005Metric" (layer "B.Cu")
    (at 157.925 100.55 -90)
    (descr "Capacitor SMD 0402")
    (tags "capacitor SMD 0402")
    (property "Author" "Antmicro")
    (property "Dielectric" "X7R")
    (property "License" "Apache-2.0")
    (property "MPN" "GRM155R71H103KA88D")
    (property "Manufacturer" "Murata")
    (property "Sheetfile" "ethernet.kicad_sch")
    (property "Sheetname" "Ethernet")
    (property "Val" "10n")
    (property "Voltage" "50V")
    (property "ki_description" " ")
    (attr smd)
    (fp_text reference "C129" (at -0.04 1.52 90) (layer "B.SilkS")
        (effects (font (size 0.7 0.7) (thickness 0.15)) (justify left bottom mirror))
    )
    (fp_text value "C_10n_0402" (at 0 -1.4 90) (layer "B.Fab") hide
        (effects (font (size 0.7 0.7) (thickness 0.15)) (justify left bottom mirror))
    )
    (fp_text user "Author: Antmicro" (at -0.932 -4.17 90) (layer "B.Fab") hide
        (effects (font (size 0.7 0.7) (thickness 0.15)) (justify left bottom mirror))
    )
    (fp_text user "License: Apache-2.0" (at -0.932 -5.17 90) (layer "B.Fab") hide
        (effects (font (size 0.7 0.7) (thickness 0.15)) (justify left bottom mirror))
    )
    (fp_text user "${REFERENCE}" (at -0.932 -3.168 90) (layer "B.Fab") hide
        (effects (font (size 0.7 0.7) (thickness 0.15)) (justify left bottom mirror))
    )
    (fp_rect (start -0.94 0.47) (end 0.94 -0.47)
      (stroke (width 0.05) (type solid)) (fill none) (layer "B.CrtYd"))
    (fp_rect (start -0.499 0.249) (end 0.499 -0.249)
      (stroke (width 0.15) (type solid)) (fill none) (layer "B.Fab"))
    (pad "1" smd roundrect (at -0.484 0 270) (size 0.59 0.64) (layers "B.Cu" "B.Paste" "B.Mask") (roundrect_rratio 0.25)
      (net 177 "/Ethernet/AVDDL") (pintype "passive"))
    (pad "2" smd roundrect (at 0.484 0 270) (size 0.59 0.64) (layers "B.Cu" "B.Paste" "B.Mask") (roundrect_rratio 0.25)
      (net 9 "GND") (pintype "passive"))
  )
	(footprint "data-center-rdimm-ddr4-tester-footprints:C_0402_1005Metric" (layer "B.Cu")
    (at 156.486328 93.020008 -90)
    (descr "Capacitor SMD 0402")
    (tags "capacitor SMD 0402")
    (property "Author" "Antmicro")
    (property "Dielectric" "X7R")
    (property "License" "Apache-2.0")
    (property "MPN" "GRM155R71H103KA88D")
    (property "Manufacturer" "Murata")
    (property "Sheetfile" "ethernet.kicad_sch")
    (property "Sheetname" "Ethernet")
    (property "Val" "10n")
    (property "Voltage" "50V")
    (property "ki_description" " ")
    (attr smd)
    (fp_text reference "C131" (at -1.449008 -6.503672 90) (layer "B.SilkS")
        (effects (font (size 0.7 0.7) (thickness 0.15)) (justify left bottom mirror))
    )
    (fp_text value "C_10n_0402" (at 0 -1.4 90) (layer "B.Fab") hide
        (effects (font (size 0.7 0.7) (thickness 0.15)) (justify left bottom mirror))
    )
    (fp_text user "${REFERENCE}" (at -0.932 -3.168 90) (layer "B.Fab") hide
        (effects (font (size 0.7 0.7) (thickness 0.15)) (justify left bottom mirror))
    )
    (fp_text user "License: Apache-2.0" (at -0.932 -5.17 90) (layer "B.Fab") hide
        (effects (font (size 0.7 0.7) (thickness 0.15)) (justify left bottom mirror))
    )
    (fp_text user "Author: Antmicro" (at -0.932 -4.17 90) (layer "B.Fab") hide
        (effects (font (size 0.7 0.7) (thickness 0.15)) (justify left bottom mirror))
    )
    (fp_rect (start -0.94 0.47) (end 0.94 -0.47)
      (stroke (width 0.05) (type solid)) (fill none) (layer "B.CrtYd"))
    (fp_rect (start -0.499 0.249) (end 0.499 -0.249)
      (stroke (width 0.15) (type solid)) (fill none) (layer "B.Fab"))
    (pad "1" smd roundrect (at -0.484 0 270) (size 0.59 0.64) (layers "B.Cu" "B.Paste" "B.Mask") (roundrect_rratio 0.25)
      (net 143 "3V3_SYS") (pintype "passive"))
    (pad "2" smd roundrect (at 0.484 0 270) (size 0.59 0.64) (layers "B.Cu" "B.Paste" "B.Mask") (roundrect_rratio 0.25)
      (net 9 "GND") (pintype "passive"))
  )
	(footprint "data-center-rdimm-ddr4-tester-footprints:C_0402_1005Metric" (layer "B.Cu")
    (at 154.1 100.025 180)
    (descr "Capacitor SMD 0402")
    (tags "capacitor SMD 0402")
    (property "Author" "Antmicro")
    (property "Dielectric" "")
    (property "License" "Apache-2.0")
    (property "MPN" "GRM155R61A475MEAAD")
    (property "Manufacturer" "Murata")
    (property "Sheetfile" "ethernet.kicad_sch")
    (property "Sheetname" "Ethernet")
    (property "Val" "4u7")
    (property "Voltage" "")
    (property "ki_description" " ")
    (attr smd)
    (fp_text reference "C132" (at 1.02 -0.345) (layer "B.SilkS")
        (effects (font (size 0.7 0.7) (thickness 0.15)) (justify left bottom mirror))
    )
    (fp_text value "C_4u7_0402" (at 0 -1.4) (layer "B.Fab") hide
        (effects (font (size 0.7 0.7) (thickness 0.15)) (justify left bottom mirror))
    )
    (fp_text user "Author: Antmicro" (at -0.932 -4.17) (layer "B.Fab") hide
        (effects (font (size 0.7 0.7) (thickness 0.15)) (justify left bottom mirror))
    )
    (fp_text user "License: Apache-2.0" (at -0.932 -5.17) (layer "B.Fab") hide
        (effects (font (size 0.7 0.7) (thickness 0.15)) (justify left bottom mirror))
    )
    (fp_text user "${REFERENCE}" (at -0.932 -3.168) (layer "B.Fab") hide
        (effects (font (size 0.7 0.7) (thickness 0.15)) (justify left bottom mirror))
    )
    (fp_rect (start -0.94 0.47) (end 0.94 -0.47)
      (stroke (width 0.05) (type solid)) (fill none) (layer "B.CrtYd"))
    (fp_rect (start -0.499 0.249) (end 0.499 -0.249)
      (stroke (width 0.15) (type solid)) (fill none) (layer "B.Fab"))
    (pad "1" smd roundrect (at -0.484 0 180) (size 0.59 0.64) (layers "B.Cu" "B.Paste" "B.Mask") (roundrect_rratio 0.25)
      (net 179 "/Ethernet/AVDDH") (pintype "passive"))
    (pad "2" smd roundrect (at 0.484 0 180) (size 0.59 0.64) (layers "B.Cu" "B.Paste" "B.Mask") (roundrect_rratio 0.25)
      (net 9 "GND") (pintype "passive"))
  )
	(footprint "data-center-rdimm-ddr4-tester-footprints:C_0402_1005Metric" (layer "B.Cu")
    (at 160.75 99.575)
    (descr "Capacitor SMD 0402")
    (tags "capacitor SMD 0402")
    (property "Author" "Antmicro")
    (property "Dielectric" "X7R")
    (property "License" "Apache-2.0")
    (property "MPN" "GRM155R71H103KA88D")
    (property "Manufacturer" "Murata")
    (property "Sheetfile" "ethernet.kicad_sch")
    (property "Sheetname" "Ethernet")
    (property "Val" "10n")
    (property "Voltage" "50V")
    (property "ki_description" " ")
    (attr smd)
    (fp_text reference "C134" (at 3.69 0.355 180) (layer "B.SilkS")
        (effects (font (size 0.7 0.7) (thickness 0.15)) (justify left bottom mirror))
    )
    (fp_text value "C_10n_0402" (at 0 -1.4 180) (layer "B.Fab") hide
        (effects (font (size 0.7 0.7) (thickness 0.15)) (justify left bottom mirror))
    )
    (fp_text user "${REFERENCE}" (at -0.932 -3.168 180) (layer "B.Fab") hide
        (effects (font (size 0.7 0.7) (thickness 0.15)) (justify left bottom mirror))
    )
    (fp_text user "Author: Antmicro" (at -0.932 -4.17 180) (layer "B.Fab") hide
        (effects (font (size 0.7 0.7) (thickness 0.15)) (justify left bottom mirror))
    )
    (fp_text user "License: Apache-2.0" (at -0.932 -5.17 180) (layer "B.Fab") hide
        (effects (font (size 0.7 0.7) (thickness 0.15)) (justify left bottom mirror))
    )
    (fp_rect (start -0.94 0.47) (end 0.94 -0.47)
      (stroke (width 0.05) (type solid)) (fill none) (layer "B.CrtYd"))
    (fp_rect (start -0.499 0.249) (end 0.499 -0.249)
      (stroke (width 0.15) (type solid)) (fill none) (layer "B.Fab"))
    (pad "1" smd roundrect (at -0.484 0) (size 0.59 0.64) (layers "B.Cu" "B.Paste" "B.Mask") (roundrect_rratio 0.25)
      (net 177 "/Ethernet/AVDDL") (pintype "passive"))
    (pad "2" smd roundrect (at 0.484 0) (size 0.59 0.64) (layers "B.Cu" "B.Paste" "B.Mask") (roundrect_rratio 0.25)
      (net 9 "GND") (pintype "passive"))
  )
	(footprint "data-center-rdimm-ddr4-tester-footprints:C_0402_1005Metric" (layer "B.Cu")
    (at 152.786328 95.520008 -90)
    (descr "Capacitor SMD 0402")
    (tags "capacitor SMD 0402")
    (property "Author" "Antmicro")
    (property "Dielectric" "X7R")
    (property "License" "Apache-2.0")
    (property "MPN" "GRM155R71H103KA88D")
    (property "Manufacturer" "Murata")
    (property "Sheetfile" "ethernet.kicad_sch")
    (property "Sheetname" "Ethernet")
    (property "Val" "10n")
    (property "Voltage" "50V")
    (property "ki_description" " ")
    (attr smd)
    (fp_text reference "C136" (at -1.400008 0.516328 90) (layer "B.SilkS")
        (effects (font (size 0.7 0.7) (thickness 0.15)) (justify left bottom mirror))
    )
    (fp_text value "C_10n_0402" (at 0 -1.4 90) (layer "B.Fab") hide
        (effects (font (size 0.7 0.7) (thickness 0.15)) (justify left bottom mirror))
    )
    (fp_text user "${REFERENCE}" (at -0.932 -3.168 90) (layer "B.Fab") hide
        (effects (font (size 0.7 0.7) (thickness 0.15)) (justify left bottom mirror))
    )
    (fp_text user "Author: Antmicro" (at -0.932 -4.17 90) (layer "B.Fab") hide
        (effects (font (size 0.7 0.7) (thickness 0.15)) (justify left bottom mirror))
    )
    (fp_text user "License: Apache-2.0" (at -0.932 -5.17 90) (layer "B.Fab") hide
        (effects (font (size 0.7 0.7) (thickness 0.15)) (justify left bottom mirror))
    )
    (fp_rect (start -0.94 0.47) (end 0.94 -0.47)
      (stroke (width 0.05) (type solid)) (fill none) (layer "B.CrtYd"))
    (fp_rect (start -0.499 0.249) (end 0.499 -0.249)
      (stroke (width 0.15) (type solid)) (fill none) (layer "B.Fab"))
    (pad "1" smd roundrect (at -0.484 0 270) (size 0.59 0.64) (layers "B.Cu" "B.Paste" "B.Mask") (roundrect_rratio 0.25)
      (net 143 "3V3_SYS") (pintype "passive"))
    (pad "2" smd roundrect (at 0.484 0 270) (size 0.59 0.64) (layers "B.Cu" "B.Paste" "B.Mask") (roundrect_rratio 0.25)
      (net 9 "GND") (pintype "passive"))
  )
	(footprint "data-center-rdimm-ddr4-tester-footprints:C_0402_1005Metric" (layer "B.Cu")
    (at 161.9 101.2 -90)
    (descr "Capacitor SMD 0402")
    (tags "capacitor SMD 0402")
    (property "Author" "Antmicro")
    (property "Dielectric" "")
    (property "License" "Apache-2.0")
    (property "MPN" "GRM155R61A475MEAAD")
    (property "Manufacturer" "Murata")
    (property "Sheetfile" "ethernet.kicad_sch")
    (property "Sheetname" "Ethernet")
    (property "Val" "4u7")
    (property "Voltage" "")
    (property "ki_description" " ")
    (attr smd)
    (fp_text reference "C137" (at -0.55 1.57 90) (layer "B.SilkS")
        (effects (font (size 0.7 0.7) (thickness 0.15)) (justify left bottom mirror))
    )
    (fp_text value "C_4u7_0402" (at 0 -1.4 90) (layer "B.Fab") hide
        (effects (font (size 0.7 0.7) (thickness 0.15)) (justify left bottom mirror))
    )
    (fp_text user "License: Apache-2.0" (at -0.932 -5.17 90) (layer "B.Fab") hide
        (effects (font (size 0.7 0.7) (thickness 0.15)) (justify left bottom mirror))
    )
    (fp_text user "${REFERENCE}" (at -0.932 -3.168 90) (layer "B.Fab") hide
        (effects (font (size 0.7 0.7) (thickness 0.15)) (justify left bottom mirror))
    )
    (fp_text user "Author: Antmicro" (at -0.932 -4.17 90) (layer "B.Fab") hide
        (effects (font (size 0.7 0.7) (thickness 0.15)) (justify left bottom mirror))
    )
    (fp_rect (start -0.94 0.47) (end 0.94 -0.47)
      (stroke (width 0.05) (type solid)) (fill none) (layer "B.CrtYd"))
    (fp_rect (start -0.499 0.249) (end 0.499 -0.249)
      (stroke (width 0.15) (type solid)) (fill none) (layer "B.Fab"))
    (pad "1" smd roundrect (at -0.484 0 270) (size 0.59 0.64) (layers "B.Cu" "B.Paste" "B.Mask") (roundrect_rratio 0.25)
      (net 179 "/Ethernet/AVDDH") (pintype "passive"))
    (pad "2" smd roundrect (at 0.484 0 270) (size 0.59 0.64) (layers "B.Cu" "B.Paste" "B.Mask") (roundrect_rratio 0.25)
      (net 9 "GND") (pintype "passive"))
  )
	(footprint "data-center-rdimm-ddr4-tester-footprints:C_0402_1005Metric" (layer "B.Cu")
    (at 158.486328 93.020008 -90)
    (descr "Capacitor SMD 0402")
    (tags "capacitor SMD 0402")
    (property "Author" "Antmicro")
    (property "Dielectric" "X7R")
    (property "License" "Apache-2.0")
    (property "MPN" "GRM155R71H103KA88D")
    (property "Manufacturer" "Murata")
    (property "Sheetfile" "ethernet.kicad_sch")
    (property "Sheetname" "Ethernet")
    (property "Val" "10n")
    (property "Voltage" "50V")
    (property "ki_description" " ")
    (attr smd)
    (fp_text reference "C138" (at -1.449008 -6.503672 90) (layer "B.SilkS")
        (effects (font (size 0.7 0.7) (thickness 0.15)) (justify left bottom mirror))
    )
    (fp_text value "C_10n_0402" (at 0 -1.4 90) (layer "B.Fab") hide
        (effects (font (size 0.7 0.7) (thickness 0.15)) (justify left bottom mirror))
    )
    (fp_text user "License: Apache-2.0" (at -0.932 -5.17 90) (layer "B.Fab") hide
        (effects (font (size 0.7 0.7) (thickness 0.15)) (justify left bottom mirror))
    )
    (fp_text user "${REFERENCE}" (at -0.932 -3.168 90) (layer "B.Fab") hide
        (effects (font (size 0.7 0.7) (thickness 0.15)) (justify left bottom mirror))
    )
    (fp_text user "Author: Antmicro" (at -0.932 -4.17 90) (layer "B.Fab") hide
        (effects (font (size 0.7 0.7) (thickness 0.15)) (justify left bottom mirror))
    )
    (fp_rect (start -0.94 0.47) (end 0.94 -0.47)
      (stroke (width 0.05) (type solid)) (fill none) (layer "B.CrtYd"))
    (fp_rect (start -0.499 0.249) (end 0.499 -0.249)
      (stroke (width 0.15) (type solid)) (fill none) (layer "B.Fab"))
    (pad "1" smd roundrect (at -0.484 0 270) (size 0.59 0.64) (layers "B.Cu" "B.Paste" "B.Mask") (roundrect_rratio 0.25)
      (net 306 "1V2_SYS") (pintype "passive"))
    (pad "2" smd roundrect (at 0.484 0 270) (size 0.59 0.64) (layers "B.Cu" "B.Paste" "B.Mask") (roundrect_rratio 0.25)
      (net 9 "GND") (pintype "passive"))
  )
	(footprint "data-center-rdimm-ddr4-tester-footprints:C_0402_1005Metric" (layer "B.Cu")
    (at 162.9 101.2 -90)
    (descr "Capacitor SMD 0402")
    (tags "capacitor SMD 0402")
    (property "Author" "Antmicro")
    (property "Dielectric" "")
    (property "License" "Apache-2.0")
    (property "MPN" "GRM155R61A475MEAAD")
    (property "Manufacturer" "Murata")
    (property "Sheetfile" "ethernet.kicad_sch")
    (property "Sheetname" "Ethernet")
    (property "Val" "4u7")
    (property "Voltage" "")
    (property "ki_description" " ")
    (attr smd)
    (fp_text reference "C140" (at -0.55 1.57 90) (layer "B.SilkS")
        (effects (font (size 0.7 0.7) (thickness 0.15)) (justify left bottom mirror))
    )
    (fp_text value "C_4u7_0402" (at 0 -1.4 90) (layer "B.Fab") hide
        (effects (font (size 0.7 0.7) (thickness 0.15)) (justify left bottom mirror))
    )
    (fp_text user "License: Apache-2.0" (at -0.932 -5.17 90) (layer "B.Fab") hide
        (effects (font (size 0.7 0.7) (thickness 0.15)) (justify left bottom mirror))
    )
    (fp_text user "Author: Antmicro" (at -0.932 -4.17 90) (layer "B.Fab") hide
        (effects (font (size 0.7 0.7) (thickness 0.15)) (justify left bottom mirror))
    )
    (fp_text user "${REFERENCE}" (at -0.932 -3.168 90) (layer "B.Fab") hide
        (effects (font (size 0.7 0.7) (thickness 0.15)) (justify left bottom mirror))
    )
    (fp_rect (start -0.94 0.47) (end 0.94 -0.47)
      (stroke (width 0.05) (type solid)) (fill none) (layer "B.CrtYd"))
    (fp_rect (start -0.499 0.249) (end 0.499 -0.249)
      (stroke (width 0.15) (type solid)) (fill none) (layer "B.Fab"))
    (pad "1" smd roundrect (at -0.484 0 270) (size 0.59 0.64) (layers "B.Cu" "B.Paste" "B.Mask") (roundrect_rratio 0.25)
      (net 179 "/Ethernet/AVDDH") (pintype "passive"))
    (pad "2" smd roundrect (at 0.484 0 270) (size 0.59 0.64) (layers "B.Cu" "B.Paste" "B.Mask") (roundrect_rratio 0.25)
      (net 9 "GND") (pintype "passive"))
  )
)
